(kicad_pcb
	(version 20260206)
	(generator "pcbnew")
	(generator_version "10.0")
	(general
		(thickness 1.6)
		(legacy_teardrops no)
	)
	(paper "A4")
	(title_block
		(title "04192023_DAF0TMB3IC0_F0TG_MB_C_brd_V02_OCP.brd")
		(comment 1 "Grand Teton / footprints 1462-1468 of 8354")
	)
	(layers
		(0 "F.Cu" signal "TOP")
		(4 "In1.Cu" signal "GND")
		(6 "In2.Cu" signal "IN1")
		(8 "In3.Cu" signal "GND1")
		(10 "In4.Cu" signal "IN2")
		(12 "In5.Cu" signal "GND2")
		(14 "In6.Cu" signal "IN3")
		(16 "In7.Cu" signal "GND3")
		(18 "In8.Cu" signal "VCC")
		(20 "In9.Cu" signal "VCC1")
		(22 "In10.Cu" signal "GND4")
		(24 "In11.Cu" signal "IN4")
		(26 "In12.Cu" signal "GND5")
		(28 "In13.Cu" signal "IN5")
		(30 "In14.Cu" signal "GND6")
		(32 "In15.Cu" signal "IN6")
		(34 "In16.Cu" signal "GND7")
		(2 "B.Cu" signal "BOTTOM")
		(9 "F.Adhes" user "F.Adhesive")
		(11 "B.Adhes" user "B.Adhesive")
		(13 "F.Paste" user "Package Geometry/Pastemask Top")
		(15 "B.Paste" user "Package Geometry/Pastemask Bottom")
		(5 "F.SilkS" user "Ref Des/Silkscreen Top")
		(7 "B.SilkS" user "Ref Des/Silkscreen Bottom")
		(1 "F.Mask" user "Board Geometry/Soldermask Top")
		(3 "B.Mask" user "Board Geometry/Soldermask Bottom")
		(17 "Dwgs.User" user "User.Drawings")
		(19 "Cmts.User" user "User.Comments")
		(21 "Eco1.User" user "User.Eco1")
		(23 "Eco2.User" user "User.Eco2")
		(25 "Edge.Cuts" user "Board Geometry/Outline")
		(27 "Margin" user)
		(31 "F.CrtYd" user "Package Geometry/Place Bound Top")
		(29 "B.CrtYd" user "Package Geometry/Place Bound Bottom")
		(35 "F.Fab" user "Ref Des/Assembly Top")
		(33 "B.Fab" user "Ref Des/Assembly Bottom")
	)
	(footprint ""
		(layer "F.Cu")
		(at 376.352308 -184.478168 -90)
		(property "Reference" "PR496"
			(at 0 0 270)
			(layer "F.SilkS")
			(hide yes)
			(effects
				(font
					(size 1.27 1.27)
				)
			)
		)
		(property "Value" ""
			(at 0 0 270)
			(layer "F.Fab")
			(effects
				(font
					(size 1.27 1.27)
				)
			)
		)
		(duplicate_pad_numbers_are_jumpers no)
		(fp_line
			(start -0.7874 0.4064)
			(end -0.7874 -0.4064)
			(stroke
				(width 0.1524)
				(type default)
			)
			(layer "F.SilkS")
		)
		(fp_line
			(start 0.7874 0.4064)
			(end -0.7874 0.4064)
			(stroke
				(width 0.1524)
				(type default)
			)
			(layer "F.SilkS")
		)
		(fp_line
			(start -0.7874 -0.4064)
			(end 0.7874 -0.4064)
			(stroke
				(width 0.1524)
				(type default)
			)
			(layer "F.SilkS")
		)
		(fp_line
			(start 0.7874 -0.4064)
			(end 0.7874 0.4064)
			(stroke
				(width 0.1524)
				(type default)
			)
			(layer "F.SilkS")
		)
		(fp_line
			(start -0.67945 0.3048)
			(end -0.67945 -0.305054)
			(stroke
				(width 0.1)
				(type default)
			)
			(layer "F.Fab")
		)
		(fp_line
			(start -0.12065 0.3048)
			(end -0.67945 0.3048)
			(stroke
				(width 0.1)
				(type default)
			)
			(layer "F.Fab")
		)
		(fp_line
			(start 0.120396 0.3048)
			(end 0.120396 0.2794)
			(stroke
				(width 0.1)
				(type default)
			)
			(layer "F.Fab")
		)
		(fp_line
			(start 0.67945 0.3048)
			(end 0.120396 0.3048)
			(stroke
				(width 0.1)
				(type default)
			)
			(layer "F.Fab")
		)
		(fp_line
			(start -0.12065 0.2794)
			(end -0.12065 0.3048)
			(stroke
				(width 0.1)
				(type default)
			)
			(layer "F.Fab")
		)
		(fp_line
			(start 0.120396 0.2794)
			(end -0.12065 0.2794)
			(stroke
				(width 0.1)
				(type default)
			)
			(layer "F.Fab")
		)
		(fp_line
			(start -0.12065 -0.2794)
			(end 0.12065 -0.2794)
			(stroke
				(width 0.1)
				(type default)
			)
			(layer "F.Fab")
		)
		(fp_line
			(start 0.12065 -0.2794)
			(end 0.12065 -0.3048)
			(stroke
				(width 0.1)
				(type default)
			)
			(layer "F.Fab")
		)
		(fp_line
			(start 0.12065 -0.3048)
			(end 0.67945 -0.3048)
			(stroke
				(width 0.1)
				(type default)
			)
			(layer "F.Fab")
		)
		(fp_line
			(start 0.67945 -0.3048)
			(end 0.67945 0.3048)
			(stroke
				(width 0.1)
				(type default)
			)
			(layer "F.Fab")
		)
		(fp_line
			(start -0.67945 -0.305054)
			(end -0.12065 -0.305054)
			(stroke
				(width 0.1)
				(type default)
			)
			(layer "F.Fab")
		)
		(fp_line
			(start -0.12065 -0.305054)
			(end -0.12065 -0.2794)
			(stroke
				(width 0.1)
				(type default)
			)
			(layer "F.Fab")
		)
		(pad "1" smd circle
			(at -0.40005 0 270)
			(size 0 0)
			(layers "F.Cu" "F.Mask" "F.Paste")
			(net "SW_PVDDCR_CPU0_P0_SW2_RC")
		)
		(pad "2" smd circle
			(at 0.40005 0 270)
			(size 0 0)
			(layers "F.Cu" "F.Mask" "F.Paste")
			(net "GND")
		)
	)
	(footprint ""
		(layer "F.Cu")
		(at 142.595092 -376.85726 180)
		(property "Reference" "C770"
			(at 0 0 180)
			(layer "F.SilkS")
			(hide yes)
			(effects
				(font
					(size 1.27 1.27)
				)
			)
		)
		(property "Value" ""
			(at 0 0 180)
			(layer "F.Fab")
			(effects
				(font
					(size 1.27 1.27)
				)
			)
		)
		(duplicate_pad_numbers_are_jumpers no)
		(fp_line
			(start 0.299974 0.150114)
			(end -0.299974 0.150114)
			(stroke
				(width 0.1)
				(type default)
			)
			(layer "F.Fab")
		)
		(fp_line
			(start 0.299974 -0.150114)
			(end 0.299974 0.150114)
			(stroke
				(width 0.1)
				(type default)
			)
			(layer "F.Fab")
		)
		(fp_line
			(start -0.299974 0.150114)
			(end -0.299974 -0.150114)
			(stroke
				(width 0.1)
				(type default)
			)
			(layer "F.Fab")
		)
		(fp_line
			(start -0.299974 -0.150114)
			(end 0.299974 -0.150114)
			(stroke
				(width 0.1)
				(type default)
			)
			(layer "F.Fab")
		)
		(pad "1" smd rect
			(at -0.2667 0 180)
			(size 0.3048 0.381)
			(layers "F.Cu" "F.Mask" "F.Paste")
			(net "P5E_CPU1_P2_TX_C_DN<1>")
		)
		(pad "2" smd rect
			(at 0.2667 0 180)
			(size 0.3048 0.381)
			(layers "F.Cu" "F.Mask" "F.Paste")
			(net "P5E_CPU1_P2_TX_DN<1>")
		)
	)
	(footprint ""
		(layer "F.Cu")
		(at 444.598552 -25.477978)
		(property "Reference" "PC2160"
			(at 0 0 0)
			(layer "F.SilkS")
			(hide yes)
			(effects
				(font
					(size 1.27 1.27)
				)
			)
		)
		(property "Value" ""
			(at 0 0 0)
			(layer "F.Fab")
			(effects
				(font
					(size 1.27 1.27)
				)
			)
		)
		(duplicate_pad_numbers_are_jumpers no)
		(fp_line
			(start -0.7874 -0.4064)
			(end 0.7874 -0.4064)
			(stroke
				(width 0.1524)
				(type default)
			)
			(layer "F.SilkS")
		)
		(fp_line
			(start -0.7874 0.4064)
			(end -0.7874 -0.4064)
			(stroke
				(width 0.1524)
				(type default)
			)
			(layer "F.SilkS")
		)
		(fp_line
			(start 0.7874 -0.4064)
			(end 0.7874 0.4064)
			(stroke
				(width 0.1524)
				(type default)
			)
			(layer "F.SilkS")
		)
		(fp_line
			(start 0.7874 0.4064)
			(end -0.7874 0.4064)
			(stroke
				(width 0.1524)
				(type default)
			)
			(layer "F.SilkS")
		)
		(fp_line
			(start -0.67945 -0.305054)
			(end -0.12065 -0.305054)
			(stroke
				(width 0.1)
				(type default)
			)
			(layer "F.Fab")
		)
		(fp_line
			(start -0.67945 0.3048)
			(end -0.67945 -0.305054)
			(stroke
				(width 0.1)
				(type default)
			)
			(layer "F.Fab")
		)
		(fp_line
			(start -0.12065 -0.305054)
			(end -0.12065 -0.2794)
			(stroke
				(width 0.1)
				(type default)
			)
			(layer "F.Fab")
		)
		(fp_line
			(start -0.12065 -0.2794)
			(end 0.12065 -0.2794)
			(stroke
				(width 0.1)
				(type default)
			)
			(layer "F.Fab")
		)
		(fp_line
			(start -0.12065 0.2794)
			(end -0.12065 0.3048)
			(stroke
				(width 0.1)
				(type default)
			)
			(layer "F.Fab")
		)
		(fp_line
			(start -0.12065 0.3048)
			(end -0.67945 0.3048)
			(stroke
				(width 0.1)
				(type default)
			)
			(layer "F.Fab")
		)
		(fp_line
			(start 0.120396 0.2794)
			(end -0.12065 0.2794)
			(stroke
				(width 0.1)
				(type default)
			)
			(layer "F.Fab")
		)
		(fp_line
			(start 0.120396 0.3048)
			(end 0.120396 0.2794)
			(stroke
				(width 0.1)
				(type default)
			)
			(layer "F.Fab")
		)
		(fp_line
			(start 0.12065 -0.3048)
			(end 0.67945 -0.3048)
			(stroke
				(width 0.1)
				(type default)
			)
			(layer "F.Fab")
		)
		(fp_line
			(start 0.12065 -0.2794)
			(end 0.12065 -0.3048)
			(stroke
				(width 0.1)
				(type default)
			)
			(layer "F.Fab")
		)
		(fp_line
			(start 0.67945 -0.3048)
			(end 0.67945 0.3048)
			(stroke
				(width 0.1)
				(type default)
			)
			(layer "F.Fab")
		)
		(fp_line
			(start 0.67945 0.3048)
			(end 0.120396 0.3048)
			(stroke
				(width 0.1)
				(type default)
			)
			(layer "F.Fab")
		)
		(pad "1" smd circle
			(at -0.40005 0)
			(size 0 0)
			(layers "F.Cu" "F.Mask" "F.Paste")
			(net "P12V_OCP_SFF")
		)
		(pad "2" smd circle
			(at 0.40005 0)
			(size 0 0)
			(layers "F.Cu" "F.Mask" "F.Paste")
			(net "GND")
		)
	)
	(footprint ""
		(layer "F.Cu")
		(at 426.979588 -390.68629)
		(property "Reference" "R1060"
			(at 0 0 0)
			(layer "F.SilkS")
			(hide yes)
			(effects
				(font
					(size 1.27 1.27)
				)
			)
		)
		(property "Value" ""
			(at 0 0 0)
			(layer "F.Fab")
			(effects
				(font
					(size 1.27 1.27)
				)
			)
		)
		(duplicate_pad_numbers_are_jumpers no)
		(fp_line
			(start -0.32512 -0.175006)
			(end 0.32512 -0.175006)
			(stroke
				(width 0.1)
				(type default)
			)
			(layer "F.Fab")
		)
		(fp_line
			(start -0.32512 0.175006)
			(end -0.32512 -0.175006)
			(stroke
				(width 0.1)
				(type default)
			)
			(layer "F.Fab")
		)
		(fp_line
			(start 0.32512 -0.175006)
			(end 0.32512 0.175006)
			(stroke
				(width 0.1)
				(type default)
			)
			(layer "F.Fab")
		)
		(fp_line
			(start 0.32512 0.175006)
			(end -0.32512 0.175006)
			(stroke
				(width 0.1)
				(type default)
			)
			(layer "F.Fab")
		)
		(pad "1" smd rect
			(at -0.2667 0)
			(size 0.3048 0.381)
			(layers "F.Cu" "F.Mask" "F.Paste")
			(net "RT_CPU0_P2_ADDR1")
		)
		(pad "2" smd rect
			(at 0.2667 0 180)
			(size 0.3048 0.381)
			(layers "F.Cu" "F.Mask" "F.Paste")
			(net "GND")
		)
	)
	(footprint ""
		(layer "F.Cu")
		(at 458.244194 -46.264576 -90)
		(property "Reference" "PR832"
			(at 0 0 270)
			(layer "F.SilkS")
			(hide yes)
			(effects
				(font
					(size 1.27 1.27)
				)
			)
		)
		(property "Value" ""
			(at 0 0 270)
			(layer "F.Fab")
			(effects
				(font
					(size 1.27 1.27)
				)
			)
		)
		(duplicate_pad_numbers_are_jumpers no)
		(fp_line
			(start -0.7874 0.4064)
			(end -0.7874 -0.4064)
			(stroke
				(width 0.1524)
				(type default)
			)
			(layer "F.SilkS")
		)
		(fp_line
			(start 0.7874 0.4064)
			(end -0.7874 0.4064)
			(stroke
				(width 0.1524)
				(type default)
			)
			(layer "F.SilkS")
		)
		(fp_line
			(start -0.7874 -0.4064)
			(end 0.7874 -0.4064)
			(stroke
				(width 0.1524)
				(type default)
			)
			(layer "F.SilkS")
		)
		(fp_line
			(start 0.7874 -0.4064)
			(end 0.7874 0.4064)
			(stroke
				(width 0.1524)
				(type default)
			)
			(layer "F.SilkS")
		)
		(fp_line
			(start -0.67945 0.3048)
			(end -0.67945 -0.305054)
			(stroke
				(width 0.1)
				(type default)
			)
			(layer "F.Fab")
		)
		(fp_line
			(start -0.12065 0.3048)
			(end -0.67945 0.3048)
			(stroke
				(width 0.1)
				(type default)
			)
			(layer "F.Fab")
		)
		(fp_line
			(start 0.120396 0.3048)
			(end 0.120396 0.2794)
			(stroke
				(width 0.1)
				(type default)
			)
			(layer "F.Fab")
		)
		(fp_line
			(start 0.67945 0.3048)
			(end 0.120396 0.3048)
			(stroke
				(width 0.1)
				(type default)
			)
			(layer "F.Fab")
		)
		(fp_line
			(start -0.12065 0.2794)
			(end -0.12065 0.3048)
			(stroke
				(width 0.1)
				(type default)
			)
			(layer "F.Fab")
		)
		(fp_line
			(start 0.120396 0.2794)
			(end -0.12065 0.2794)
			(stroke
				(width 0.1)
				(type default)
			)
			(layer "F.Fab")
		)
		(fp_line
			(start -0.12065 -0.2794)
			(end 0.12065 -0.2794)
			(stroke
				(width 0.1)
				(type default)
			)
			(layer "F.Fab")
		)
		(fp_line
			(start 0.12065 -0.2794)
			(end 0.12065 -0.3048)
			(stroke
				(width 0.1)
				(type default)
			)
			(layer "F.Fab")
		)
		(fp_line
			(start 0.12065 -0.3048)
			(end 0.67945 -0.3048)
			(stroke
				(width 0.1)
				(type default)
			)
			(layer "F.Fab")
		)
		(fp_line
			(start 0.67945 -0.3048)
			(end 0.67945 0.3048)
			(stroke
				(width 0.1)
				(type default)
			)
			(layer "F.Fab")
		)
		(fp_line
			(start -0.67945 -0.305054)
			(end -0.12065 -0.305054)
			(stroke
				(width 0.1)
				(type default)
			)
			(layer "F.Fab")
		)
		(fp_line
			(start -0.12065 -0.305054)
			(end -0.12065 -0.2794)
			(stroke
				(width 0.1)
				(type default)
			)
			(layer "F.Fab")
		)
		(pad "1" smd circle
			(at -0.40005 0 270)
			(size 0 0)
			(layers "F.Cu" "F.Mask" "F.Paste")
			(net "P3V3_AUX_MODE")
		)
		(pad "2" smd circle
			(at 0.40005 0 270)
			(size 0 0)
			(layers "F.Cu" "F.Mask" "F.Paste")
			(net "GND")
		)
	)
	(footprint ""
		(layer "F.Cu")
		(at 223.70288 -44.922948)
		(property "Reference" "R3534"
			(at 0 0 0)
			(layer "F.SilkS")
			(hide yes)
			(effects
				(font
					(size 1.27 1.27)
				)
			)
		)
		(property "Value" ""
			(at 0 0 0)
			(layer "F.Fab")
			(effects
				(font
					(size 1.27 1.27)
				)
			)
		)
		(duplicate_pad_numbers_are_jumpers no)
		(fp_line
			(start -0.7874 -0.4064)
			(end 0.7874 -0.4064)
			(stroke
				(width 0.1524)
				(type default)
			)
			(layer "F.SilkS")
		)
		(fp_line
			(start -0.7874 0.4064)
			(end -0.7874 -0.4064)
			(stroke
				(width 0.1524)
				(type default)
			)
			(layer "F.SilkS")
		)
		(fp_line
			(start 0.7874 -0.4064)
			(end 0.7874 0.4064)
			(stroke
				(width 0.1524)
				(type default)
			)
			(layer "F.SilkS")
		)
		(fp_line
			(start 0.7874 0.4064)
			(end -0.7874 0.4064)
			(stroke
				(width 0.1524)
				(type default)
			)
			(layer "F.SilkS")
		)
		(fp_line
			(start -0.67945 -0.305054)
			(end -0.12065 -0.305054)
			(stroke
				(width 0.1)
				(type default)
			)
			(layer "F.Fab")
		)
		(fp_line
			(start -0.67945 0.3048)
			(end -0.67945 -0.305054)
			(stroke
				(width 0.1)
				(type default)
			)
			(layer "F.Fab")
		)
		(fp_line
			(start -0.12065 -0.305054)
			(end -0.12065 -0.2794)
			(stroke
				(width 0.1)
				(type default)
			)
			(layer "F.Fab")
		)
		(fp_line
			(start -0.12065 -0.2794)
			(end 0.12065 -0.2794)
			(stroke
				(width 0.1)
				(type default)
			)
			(layer "F.Fab")
		)
		(fp_line
			(start -0.12065 0.2794)
			(end -0.12065 0.3048)
			(stroke
				(width 0.1)
				(type default)
			)
			(layer "F.Fab")
		)
		(fp_line
			(start -0.12065 0.3048)
			(end -0.67945 0.3048)
			(stroke
				(width 0.1)
				(type default)
			)
			(layer "F.Fab")
		)
		(fp_line
			(start 0.120396 0.2794)
			(end -0.12065 0.2794)
			(stroke
				(width 0.1)
				(type default)
			)
			(layer "F.Fab")
		)
		(fp_line
			(start 0.120396 0.3048)
			(end 0.120396 0.2794)
			(stroke
				(width 0.1)
				(type default)
			)
			(layer "F.Fab")
		)
		(fp_line
			(start 0.12065 -0.3048)
			(end 0.67945 -0.3048)
			(stroke
				(width 0.1)
				(type default)
			)
			(layer "F.Fab")
		)
		(fp_line
			(start 0.12065 -0.2794)
			(end 0.12065 -0.3048)
			(stroke
				(width 0.1)
				(type default)
			)
			(layer "F.Fab")
		)
		(fp_line
			(start 0.67945 -0.3048)
			(end 0.67945 0.3048)
			(stroke
				(width 0.1)
				(type default)
			)
			(layer "F.Fab")
		)
		(fp_line
			(start 0.67945 0.3048)
			(end 0.120396 0.3048)
			(stroke
				(width 0.1)
				(type default)
			)
			(layer "F.Fab")
		)
		(pad "1" smd circle
			(at -0.40005 0)
			(size 0 0)
			(layers "F.Cu" "F.Mask" "F.Paste")
			(net "SMB_E1S_3V3AUX_ISO_SDA_R")
		)
		(pad "2" smd circle
			(at 0.40005 0)
			(size 0 0)
			(layers "F.Cu" "F.Mask" "F.Paste")
			(net "SMB_E1S_3V3AUX_ISO_SDA")
		)
	)
	(footprint ""
		(layer "F.Cu")
		(at 175.4632 -96.103948 90)
		(property "Reference" "R238"
			(at 0 0 90)
			(layer "F.SilkS")
			(hide yes)
			(effects
				(font
					(size 1.27 1.27)
				)
			)
		)
		(property "Value" ""
			(at 0 0 90)
			(layer "F.Fab")
			(effects
				(font
					(size 1.27 1.27)
				)
			)
		)
		(duplicate_pad_numbers_are_jumpers no)
		(fp_line
			(start 0.7874 -0.4064)
			(end 0.7874 0.4064)
			(stroke
				(width 0.1524)
				(type default)
			)
			(layer "F.SilkS")
		)
		(fp_line
			(start -0.7874 -0.4064)
			(end 0.7874 -0.4064)
			(stroke
				(width 0.1524)
				(type default)
			)
			(layer "F.SilkS")
		)
		(fp_line
			(start 0.7874 0.4064)
			(end -0.7874 0.4064)
			(stroke
				(width 0.1524)
				(type default)
			)
			(layer "F.SilkS")
		)
		(fp_line
			(start -0.7874 0.4064)
			(end -0.7874 -0.4064)
			(stroke
				(width 0.1524)
				(type default)
			)
			(layer "F.SilkS")
		)
		(fp_line
			(start -0.12065 -0.305054)
			(end -0.12065 -0.2794)
			(stroke
				(width 0.1)
				(type default)
			)
			(layer "F.Fab")
		)
		(fp_line
			(start -0.67945 -0.305054)
			(end -0.12065 -0.305054)
			(stroke
				(width 0.1)
				(type default)
			)
			(layer "F.Fab")
		)
		(fp_line
			(start 0.67945 -0.3048)
			(end 0.67945 0.3048)
			(stroke
				(width 0.1)
				(type default)
			)
			(layer "F.Fab")
		)
		(fp_line
			(start 0.12065 -0.3048)
			(end 0.67945 -0.3048)
			(stroke
				(width 0.1)
				(type default)
			)
			(layer "F.Fab")
		)
		(fp_line
			(start 0.12065 -0.2794)
			(end 0.12065 -0.3048)
			(stroke
				(width 0.1)
				(type default)
			)
			(layer "F.Fab")
		)
		(fp_line
			(start -0.12065 -0.2794)
			(end 0.12065 -0.2794)
			(stroke
				(width 0.1)
				(type default)
			)
			(layer "F.Fab")
		)
		(fp_line
			(start 0.120396 0.2794)
			(end -0.12065 0.2794)
			(stroke
				(width 0.1)
				(type default)
			)
			(layer "F.Fab")
		)
		(fp_line
			(start -0.12065 0.2794)
			(end -0.12065 0.3048)
			(stroke
				(width 0.1)
				(type default)
			)
			(layer "F.Fab")
		)
		(fp_line
			(start 0.67945 0.3048)
			(end 0.120396 0.3048)
			(stroke
				(width 0.1)
				(type default)
			)
			(layer "F.Fab")
		)
		(fp_line
			(start 0.120396 0.3048)
			(end 0.120396 0.2794)
			(stroke
				(width 0.1)
				(type default)
			)
			(layer "F.Fab")
		)
		(fp_line
			(start -0.12065 0.3048)
			(end -0.67945 0.3048)
			(stroke
				(width 0.1)
				(type default)
			)
			(layer "F.Fab")
		)
		(fp_line
			(start -0.67945 0.3048)
			(end -0.67945 -0.305054)
			(stroke
				(width 0.1)
				(type default)
			)
			(layer "F.Fab")
		)
		(pad "1" smd circle
			(at -0.40005 0 90)
			(size 0 0)
			(layers "F.Cu" "F.Mask" "F.Paste")
			(net "CPU0_XTRIG_L6")
		)
		(pad "2" smd circle
			(at 0.40005 0 90)
			(size 0 0)
			(layers "F.Cu" "F.Mask" "F.Paste")
			(net "FM_CPU0_XTRIG_L6")
		)
	)
)
